(kicad_pcb
	(version 20260206)
	(generator "pcbnew")
	(generator_version "10.0")
	(general
		(thickness 1.6)
		(legacy_teardrops no)
	)
	(paper "A4")
	(title_block
		(title "04192023_DAF0TMB3IC0_F0TG_MB_C_brd_V02_OCP.brd")
		(comment 1 "Grand Teton / footprints 3984-3993 of 8354")
	)
	(layers
		(0 "F.Cu" signal "TOP")
		(4 "In1.Cu" signal "GND")
		(6 "In2.Cu" signal "IN1")
		(8 "In3.Cu" signal "GND1")
		(10 "In4.Cu" signal "IN2")
		(12 "In5.Cu" signal "GND2")
		(14 "In6.Cu" signal "IN3")
		(16 "In7.Cu" signal "GND3")
		(18 "In8.Cu" signal "VCC")
		(20 "In9.Cu" signal "VCC1")
		(22 "In10.Cu" signal "GND4")
		(24 "In11.Cu" signal "IN4")
		(26 "In12.Cu" signal "GND5")
		(28 "In13.Cu" signal "IN5")
		(30 "In14.Cu" signal "GND6")
		(32 "In15.Cu" signal "IN6")
		(34 "In16.Cu" signal "GND7")
		(2 "B.Cu" signal "BOTTOM")
		(9 "F.Adhes" user "F.Adhesive")
		(11 "B.Adhes" user "B.Adhesive")
		(13 "F.Paste" user "Package Geometry/Pastemask Top")
		(15 "B.Paste" user "Package Geometry/Pastemask Bottom")
		(5 "F.SilkS" user "Ref Des/Silkscreen Top")
		(7 "B.SilkS" user "Ref Des/Silkscreen Bottom")
		(1 "F.Mask" user "Board Geometry/Soldermask Top")
		(3 "B.Mask" user "Board Geometry/Soldermask Bottom")
		(17 "Dwgs.User" user "User.Drawings")
		(19 "Cmts.User" user "User.Comments")
		(21 "Eco1.User" user "User.Eco1")
		(23 "Eco2.User" user "User.Eco2")
		(25 "Edge.Cuts" user "Board Geometry/Outline")
		(27 "Margin" user)
		(31 "F.CrtYd" user "Package Geometry/Place Bound Top")
		(29 "B.CrtYd" user "Package Geometry/Place Bound Bottom")
		(35 "F.Fab" user "Ref Des/Assembly Top")
		(33 "B.Fab" user "Ref Des/Assembly Bottom")
	)
	(footprint ""
		(layer "F.Cu")
		(at 110.620302 -389.316976 90)
		(property "Reference" "R901"
			(at 0 0 90)
			(layer "F.SilkS")
			(hide yes)
			(effects
				(font
					(size 1.27 1.27)
				)
			)
		)
		(property "Value" ""
			(at 0 0 90)
			(layer "F.Fab")
			(effects
				(font
					(size 1.27 1.27)
				)
			)
		)
		(duplicate_pad_numbers_are_jumpers no)
		(fp_line
			(start 0.32512 -0.175006)
			(end 0.32512 0.175006)
			(stroke
				(width 0.1)
				(type default)
			)
			(layer "F.Fab")
		)
		(fp_line
			(start -0.32512 -0.175006)
			(end 0.32512 -0.175006)
			(stroke
				(width 0.1)
				(type default)
			)
			(layer "F.Fab")
		)
		(fp_line
			(start 0.32512 0.175006)
			(end -0.32512 0.175006)
			(stroke
				(width 0.1)
				(type default)
			)
			(layer "F.Fab")
		)
		(fp_line
			(start -0.32512 0.175006)
			(end -0.32512 -0.175006)
			(stroke
				(width 0.1)
				(type default)
			)
			(layer "F.Fab")
		)
		(pad "1" smd rect
			(at -0.2667 0 90)
			(size 0.3048 0.381)
			(layers "F.Cu" "F.Mask" "F.Paste")
			(net "RST_RT_CPU1_P3_RESET_N")
		)
		(pad "2" smd rect
			(at 0.2667 0 270)
			(size 0.3048 0.381)
			(layers "F.Cu" "F.Mask" "F.Paste")
			(net "RST_RT_CPU1_P3_RESET_R_N")
		)
	)
	(footprint ""
		(layer "F.Cu")
		(at 108.533946 -52.86248 -90)
		(property "Reference" "R6310"
			(at 0 0 270)
			(layer "F.SilkS")
			(hide yes)
			(effects
				(font
					(size 1.27 1.27)
				)
			)
		)
		(property "Value" ""
			(at 0 0 270)
			(layer "F.Fab")
			(effects
				(font
					(size 1.27 1.27)
				)
			)
		)
		(duplicate_pad_numbers_are_jumpers no)
		(fp_line
			(start -0.7874 0.4064)
			(end -0.7874 -0.4064)
			(stroke
				(width 0.1524)
				(type default)
			)
			(layer "F.SilkS")
		)
		(fp_line
			(start 0.7874 0.4064)
			(end -0.7874 0.4064)
			(stroke
				(width 0.1524)
				(type default)
			)
			(layer "F.SilkS")
		)
		(fp_line
			(start -0.7874 -0.4064)
			(end 0.7874 -0.4064)
			(stroke
				(width 0.1524)
				(type default)
			)
			(layer "F.SilkS")
		)
		(fp_line
			(start 0.7874 -0.4064)
			(end 0.7874 0.4064)
			(stroke
				(width 0.1524)
				(type default)
			)
			(layer "F.SilkS")
		)
		(fp_line
			(start -0.67945 0.3048)
			(end -0.67945 -0.305054)
			(stroke
				(width 0.1)
				(type default)
			)
			(layer "F.Fab")
		)
		(fp_line
			(start -0.12065 0.3048)
			(end -0.67945 0.3048)
			(stroke
				(width 0.1)
				(type default)
			)
			(layer "F.Fab")
		)
		(fp_line
			(start 0.120396 0.3048)
			(end 0.120396 0.2794)
			(stroke
				(width 0.1)
				(type default)
			)
			(layer "F.Fab")
		)
		(fp_line
			(start 0.67945 0.3048)
			(end 0.120396 0.3048)
			(stroke
				(width 0.1)
				(type default)
			)
			(layer "F.Fab")
		)
		(fp_line
			(start -0.12065 0.2794)
			(end -0.12065 0.3048)
			(stroke
				(width 0.1)
				(type default)
			)
			(layer "F.Fab")
		)
		(fp_line
			(start 0.120396 0.2794)
			(end -0.12065 0.2794)
			(stroke
				(width 0.1)
				(type default)
			)
			(layer "F.Fab")
		)
		(fp_line
			(start -0.12065 -0.2794)
			(end 0.12065 -0.2794)
			(stroke
				(width 0.1)
				(type default)
			)
			(layer "F.Fab")
		)
		(fp_line
			(start 0.12065 -0.2794)
			(end 0.12065 -0.3048)
			(stroke
				(width 0.1)
				(type default)
			)
			(layer "F.Fab")
		)
		(fp_line
			(start 0.12065 -0.3048)
			(end 0.67945 -0.3048)
			(stroke
				(width 0.1)
				(type default)
			)
			(layer "F.Fab")
		)
		(fp_line
			(start 0.67945 -0.3048)
			(end 0.67945 0.3048)
			(stroke
				(width 0.1)
				(type default)
			)
			(layer "F.Fab")
		)
		(fp_line
			(start -0.67945 -0.305054)
			(end -0.12065 -0.305054)
			(stroke
				(width 0.1)
				(type default)
			)
			(layer "F.Fab")
		)
		(fp_line
			(start -0.12065 -0.305054)
			(end -0.12065 -0.2794)
			(stroke
				(width 0.1)
				(type default)
			)
			(layer "F.Fab")
		)
		(pad "1" smd circle
			(at -0.40005 0 270)
			(size 0 0)
			(layers "F.Cu" "F.Mask" "F.Paste")
			(net "USB_HUB2_TI_OVERCUR1")
		)
		(pad "2" smd circle
			(at 0.40005 0 270)
			(size 0 0)
			(layers "F.Cu" "F.Mask" "F.Paste")
			(net "USB_HUB2_TI_OVERCUR1_MRP_PROG_FUNC4")
		)
	)
	(footprint ""
		(layer "F.Cu")
		(at 373.979694 -177.532284)
		(property "Reference" "PR321"
			(at 0 0 0)
			(layer "F.SilkS")
			(hide yes)
			(effects
				(font
					(size 1.27 1.27)
				)
			)
		)
		(property "Value" ""
			(at 0 0 0)
			(layer "F.Fab")
			(effects
				(font
					(size 1.27 1.27)
				)
			)
		)
		(duplicate_pad_numbers_are_jumpers no)
		(fp_line
			(start -0.7874 -0.4064)
			(end 0.7874 -0.4064)
			(stroke
				(width 0.1524)
				(type default)
			)
			(layer "F.SilkS")
		)
		(fp_line
			(start -0.7874 0.4064)
			(end -0.7874 -0.4064)
			(stroke
				(width 0.1524)
				(type default)
			)
			(layer "F.SilkS")
		)
		(fp_line
			(start 0.7874 -0.4064)
			(end 0.7874 0.4064)
			(stroke
				(width 0.1524)
				(type default)
			)
			(layer "F.SilkS")
		)
		(fp_line
			(start 0.7874 0.4064)
			(end -0.7874 0.4064)
			(stroke
				(width 0.1524)
				(type default)
			)
			(layer "F.SilkS")
		)
		(fp_line
			(start -0.67945 -0.305054)
			(end -0.12065 -0.305054)
			(stroke
				(width 0.1)
				(type default)
			)
			(layer "F.Fab")
		)
		(fp_line
			(start -0.67945 0.3048)
			(end -0.67945 -0.305054)
			(stroke
				(width 0.1)
				(type default)
			)
			(layer "F.Fab")
		)
		(fp_line
			(start -0.12065 -0.305054)
			(end -0.12065 -0.2794)
			(stroke
				(width 0.1)
				(type default)
			)
			(layer "F.Fab")
		)
		(fp_line
			(start -0.12065 -0.2794)
			(end 0.12065 -0.2794)
			(stroke
				(width 0.1)
				(type default)
			)
			(layer "F.Fab")
		)
		(fp_line
			(start -0.12065 0.2794)
			(end -0.12065 0.3048)
			(stroke
				(width 0.1)
				(type default)
			)
			(layer "F.Fab")
		)
		(fp_line
			(start -0.12065 0.3048)
			(end -0.67945 0.3048)
			(stroke
				(width 0.1)
				(type default)
			)
			(layer "F.Fab")
		)
		(fp_line
			(start 0.120396 0.2794)
			(end -0.12065 0.2794)
			(stroke
				(width 0.1)
				(type default)
			)
			(layer "F.Fab")
		)
		(fp_line
			(start 0.120396 0.3048)
			(end 0.120396 0.2794)
			(stroke
				(width 0.1)
				(type default)
			)
			(layer "F.Fab")
		)
		(fp_line
			(start 0.12065 -0.3048)
			(end 0.67945 -0.3048)
			(stroke
				(width 0.1)
				(type default)
			)
			(layer "F.Fab")
		)
		(fp_line
			(start 0.12065 -0.2794)
			(end 0.12065 -0.3048)
			(stroke
				(width 0.1)
				(type default)
			)
			(layer "F.Fab")
		)
		(fp_line
			(start 0.67945 -0.3048)
			(end 0.67945 0.3048)
			(stroke
				(width 0.1)
				(type default)
			)
			(layer "F.Fab")
		)
		(fp_line
			(start 0.67945 0.3048)
			(end 0.120396 0.3048)
			(stroke
				(width 0.1)
				(type default)
			)
			(layer "F.Fab")
		)
		(pad "1" smd circle
			(at -0.40005 0)
			(size 0 0)
			(layers "F.Cu" "F.Mask" "F.Paste")
			(net "GND")
		)
		(pad "2" smd circle
			(at 0.40005 0)
			(size 0 0)
			(layers "F.Cu" "F.Mask" "F.Paste")
			(net "PVDDCR_CPU0_P0_LSET2")
		)
	)
	(footprint ""
		(layer "F.Cu")
		(at 257.242056 -118.91137 180)
		(property "Reference" "R3715"
			(at 0 0 180)
			(layer "F.SilkS")
			(hide yes)
			(effects
				(font
					(size 1.27 1.27)
				)
			)
		)
		(property "Value" ""
			(at 0 0 180)
			(layer "F.Fab")
			(effects
				(font
					(size 1.27 1.27)
				)
			)
		)
		(duplicate_pad_numbers_are_jumpers no)
		(fp_line
			(start 0.7874 0.4064)
			(end -0.7874 0.4064)
			(stroke
				(width 0.1524)
				(type default)
			)
			(layer "F.SilkS")
		)
		(fp_line
			(start 0.7874 -0.4064)
			(end 0.7874 0.4064)
			(stroke
				(width 0.1524)
				(type default)
			)
			(layer "F.SilkS")
		)
		(fp_line
			(start -0.7874 0.4064)
			(end -0.7874 -0.4064)
			(stroke
				(width 0.1524)
				(type default)
			)
			(layer "F.SilkS")
		)
		(fp_line
			(start -0.7874 -0.4064)
			(end 0.7874 -0.4064)
			(stroke
				(width 0.1524)
				(type default)
			)
			(layer "F.SilkS")
		)
		(fp_line
			(start 0.67945 0.3048)
			(end 0.120396 0.3048)
			(stroke
				(width 0.1)
				(type default)
			)
			(layer "F.Fab")
		)
		(fp_line
			(start 0.67945 -0.3048)
			(end 0.67945 0.3048)
			(stroke
				(width 0.1)
				(type default)
			)
			(layer "F.Fab")
		)
		(fp_line
			(start 0.12065 -0.2794)
			(end 0.12065 -0.3048)
			(stroke
				(width 0.1)
				(type default)
			)
			(layer "F.Fab")
		)
		(fp_line
			(start 0.12065 -0.3048)
			(end 0.67945 -0.3048)
			(stroke
				(width 0.1)
				(type default)
			)
			(layer "F.Fab")
		)
		(fp_line
			(start 0.120396 0.3048)
			(end 0.120396 0.2794)
			(stroke
				(width 0.1)
				(type default)
			)
			(layer "F.Fab")
		)
		(fp_line
			(start 0.120396 0.2794)
			(end -0.12065 0.2794)
			(stroke
				(width 0.1)
				(type default)
			)
			(layer "F.Fab")
		)
		(fp_line
			(start -0.12065 0.3048)
			(end -0.67945 0.3048)
			(stroke
				(width 0.1)
				(type default)
			)
			(layer "F.Fab")
		)
		(fp_line
			(start -0.12065 0.2794)
			(end -0.12065 0.3048)
			(stroke
				(width 0.1)
				(type default)
			)
			(layer "F.Fab")
		)
		(fp_line
			(start -0.12065 -0.2794)
			(end 0.12065 -0.2794)
			(stroke
				(width 0.1)
				(type default)
			)
			(layer "F.Fab")
		)
		(fp_line
			(start -0.12065 -0.305054)
			(end -0.12065 -0.2794)
			(stroke
				(width 0.1)
				(type default)
			)
			(layer "F.Fab")
		)
		(fp_line
			(start -0.67945 0.3048)
			(end -0.67945 -0.305054)
			(stroke
				(width 0.1)
				(type default)
			)
			(layer "F.Fab")
		)
		(fp_line
			(start -0.67945 -0.305054)
			(end -0.12065 -0.305054)
			(stroke
				(width 0.1)
				(type default)
			)
			(layer "F.Fab")
		)
		(pad "1" smd circle
			(at -0.40005 0 180)
			(size 0 0)
			(layers "F.Cu" "F.Mask" "F.Paste")
			(net "SMB_LM75_0_3V3AUX_SCL_R")
		)
		(pad "2" smd circle
			(at 0.40005 0 180)
			(size 0 0)
			(layers "F.Cu" "F.Mask" "F.Paste")
			(net "SMB_LM75_0_3V3AUX_SCL")
		)
	)
	(footprint ""
		(layer "F.Cu")
		(at 203.399898 -22.29993)
		(property "Reference" "H92"
			(at -5.458206 -6.02488 0)
			(unlocked yes)
			(layer "F.SilkS")
			(effects
				(font
					(size 0.7874 0.5842)
					(thickness 0.1524)
				)
				(justify left)
			)
		)
		(property "Value" ""
			(at 0 0 0)
			(layer "F.Fab")
			(effects
				(font
					(size 1.27 1.27)
				)
			)
		)
		(duplicate_pad_numbers_are_jumpers no)
		(pad "1" thru_hole circle
			(at 0 0)
			(size 10.0076 10.0076)
			(drill 5.6134)
			(layers "*.Cu" "*.Mask")
			(remove_unused_layers no)
			(net "GND")
			(clearance -1.9431)
		)
	)
	(footprint ""
		(layer "F.Cu")
		(at 322.90004 -160.50006)
		(property "Reference" "H101"
			(at -5.698998 -5.882386 0)
			(unlocked yes)
			(layer "F.SilkS")
			(effects
				(font
					(size 0.7874 0.5842)
					(thickness 0.1524)
				)
				(justify left)
			)
		)
		(property "Value" ""
			(at 0 0 0)
			(layer "F.Fab")
			(effects
				(font
					(size 1.27 1.27)
				)
			)
		)
		(duplicate_pad_numbers_are_jumpers no)
		(pad "1" thru_hole circle
			(at 0 0)
			(size 10.0076 10.0076)
			(drill 5.6134)
			(layers "*.Cu" "*.Mask")
			(remove_unused_layers no)
			(net "GND")
			(clearance -1.9431)
		)
	)
	(footprint ""
		(layer "F.Cu")
		(at 112.53216 -395.441932 -90)
		(property "Reference" "R911"
			(at 0 0 270)
			(layer "F.SilkS")
			(hide yes)
			(effects
				(font
					(size 1.27 1.27)
				)
			)
		)
		(property "Value" ""
			(at 0 0 270)
			(layer "F.Fab")
			(effects
				(font
					(size 1.27 1.27)
				)
			)
		)
		(duplicate_pad_numbers_are_jumpers no)
		(fp_line
			(start -0.32512 0.175006)
			(end -0.32512 -0.175006)
			(stroke
				(width 0.1)
				(type default)
			)
			(layer "F.Fab")
		)
		(fp_line
			(start 0.32512 0.175006)
			(end -0.32512 0.175006)
			(stroke
				(width 0.1)
				(type default)
			)
			(layer "F.Fab")
		)
		(fp_line
			(start -0.32512 -0.175006)
			(end 0.32512 -0.175006)
			(stroke
				(width 0.1)
				(type default)
			)
			(layer "F.Fab")
		)
		(fp_line
			(start 0.32512 -0.175006)
			(end 0.32512 0.175006)
			(stroke
				(width 0.1)
				(type default)
			)
			(layer "F.Fab")
		)
		(pad "1" smd rect
			(at -0.2667 0 270)
			(size 0.3048 0.381)
			(layers "F.Cu" "F.Mask" "F.Paste")
			(net "P1V8_CPU1_RT_1D")
		)
		(pad "2" smd rect
			(at 0.2667 0 90)
			(size 0.3048 0.381)
			(layers "F.Cu" "F.Mask" "F.Paste")
			(net "RST_RT_CPU1_P3_RESET_R_N")
		)
	)
	(footprint ""
		(layer "F.Cu")
		(at 135.02132 -394.35278 -90)
		(property "Reference" "R907"
			(at 0 0 270)
			(layer "F.SilkS")
			(hide yes)
			(effects
				(font
					(size 1.27 1.27)
				)
			)
		)
		(property "Value" ""
			(at 0 0 270)
			(layer "F.Fab")
			(effects
				(font
					(size 1.27 1.27)
				)
			)
		)
		(duplicate_pad_numbers_are_jumpers no)
		(fp_line
			(start -0.32512 0.175006)
			(end -0.32512 -0.175006)
			(stroke
				(width 0.1)
				(type default)
			)
			(layer "F.Fab")
		)
		(fp_line
			(start 0.32512 0.175006)
			(end -0.32512 0.175006)
			(stroke
				(width 0.1)
				(type default)
			)
			(layer "F.Fab")
		)
		(fp_line
			(start -0.32512 -0.175006)
			(end 0.32512 -0.175006)
			(stroke
				(width 0.1)
				(type default)
			)
			(layer "F.Fab")
		)
		(fp_line
			(start 0.32512 -0.175006)
			(end 0.32512 0.175006)
			(stroke
				(width 0.1)
				(type default)
			)
			(layer "F.Fab")
		)
		(pad "1" smd rect
			(at -0.2667 0 270)
			(size 0.3048 0.381)
			(layers "F.Cu" "F.Mask" "F.Paste")
			(net "RST_RT_CPU1_P3_PERST_R_N")
		)
		(pad "2" smd rect
			(at 0.2667 0 90)
			(size 0.3048 0.381)
			(layers "F.Cu" "F.Mask" "F.Paste")
			(net "GND")
		)
	)
	(footprint ""
		(layer "F.Cu")
		(at 50.832004 -408.517344 -90)
		(property "Reference" "C6632"
			(at 0 0 270)
			(layer "F.SilkS")
			(hide yes)
			(effects
				(font
					(size 1.27 1.27)
				)
			)
		)
		(property "Value" ""
			(at 0 0 270)
			(layer "F.Fab")
			(effects
				(font
					(size 1.27 1.27)
				)
			)
		)
		(duplicate_pad_numbers_are_jumpers no)
		(fp_line
			(start -0.299974 0.150114)
			(end -0.299974 -0.150114)
			(stroke
				(width 0.1)
				(type default)
			)
			(layer "F.Fab")
		)
		(fp_line
			(start 0.299974 0.150114)
			(end -0.299974 0.150114)
			(stroke
				(width 0.1)
				(type default)
			)
			(layer "F.Fab")
		)
		(fp_line
			(start -0.299974 -0.150114)
			(end 0.299974 -0.150114)
			(stroke
				(width 0.1)
				(type default)
			)
			(layer "F.Fab")
		)
		(fp_line
			(start 0.299974 -0.150114)
			(end 0.299974 0.150114)
			(stroke
				(width 0.1)
				(type default)
			)
			(layer "F.Fab")
		)
		(pad "1" smd rect
			(at -0.2667 0 270)
			(size 0.3048 0.381)
			(layers "F.Cu" "F.Mask" "F.Paste")
			(net "P5E_CPU1_P0_TX_BUF_C_DN<1>")
		)
		(pad "2" smd rect
			(at 0.2667 0 270)
			(size 0.3048 0.381)
			(layers "F.Cu" "F.Mask" "F.Paste")
			(net "P5E_CPU1_P0_TX_BUF_DN<1>")
		)
	)
	(footprint ""
		(layer "F.Cu")
		(at 382.382522 -177.532284)
		(property "Reference" "PR346"
			(at 0 0 0)
			(layer "F.SilkS")
			(hide yes)
			(effects
				(font
					(size 1.27 1.27)
				)
			)
		)
		(property "Value" ""
			(at 0 0 0)
			(layer "F.Fab")
			(effects
				(font
					(size 1.27 1.27)
				)
			)
		)
		(duplicate_pad_numbers_are_jumpers no)
		(fp_line
			(start -0.7874 -0.4064)
			(end 0.7874 -0.4064)
			(stroke
				(width 0.1524)
				(type default)
			)
			(layer "F.SilkS")
		)
		(fp_line
			(start -0.7874 0.4064)
			(end -0.7874 -0.4064)
			(stroke
				(width 0.1524)
				(type default)
			)
			(layer "F.SilkS")
		)
		(fp_line
			(start 0.7874 -0.4064)
			(end 0.7874 0.4064)
			(stroke
				(width 0.1524)
				(type default)
			)
			(layer "F.SilkS")
		)
		(fp_line
			(start 0.7874 0.4064)
			(end -0.7874 0.4064)
			(stroke
				(width 0.1524)
				(type default)
			)
			(layer "F.SilkS")
		)
		(fp_line
			(start -0.67945 -0.305054)
			(end -0.12065 -0.305054)
			(stroke
				(width 0.1)
				(type default)
			)
			(layer "F.Fab")
		)
		(fp_line
			(start -0.67945 0.3048)
			(end -0.67945 -0.305054)
			(stroke
				(width 0.1)
				(type default)
			)
			(layer "F.Fab")
		)
		(fp_line
			(start -0.12065 -0.305054)
			(end -0.12065 -0.2794)
			(stroke
				(width 0.1)
				(type default)
			)
			(layer "F.Fab")
		)
		(fp_line
			(start -0.12065 -0.2794)
			(end 0.12065 -0.2794)
			(stroke
				(width 0.1)
				(type default)
			)
			(layer "F.Fab")
		)
		(fp_line
			(start -0.12065 0.2794)
			(end -0.12065 0.3048)
			(stroke
				(width 0.1)
				(type default)
			)
			(layer "F.Fab")
		)
		(fp_line
			(start -0.12065 0.3048)
			(end -0.67945 0.3048)
			(stroke
				(width 0.1)
				(type default)
			)
			(layer "F.Fab")
		)
		(fp_line
			(start 0.120396 0.2794)
			(end -0.12065 0.2794)
			(stroke
				(width 0.1)
				(type default)
			)
			(layer "F.Fab")
		)
		(fp_line
			(start 0.120396 0.3048)
			(end 0.120396 0.2794)
			(stroke
				(width 0.1)
				(type default)
			)
			(layer "F.Fab")
		)
		(fp_line
			(start 0.12065 -0.3048)
			(end 0.67945 -0.3048)
			(stroke
				(width 0.1)
				(type default)
			)
			(layer "F.Fab")
		)
		(fp_line
			(start 0.12065 -0.2794)
			(end 0.12065 -0.3048)
			(stroke
				(width 0.1)
				(type default)
			)
			(layer "F.Fab")
		)
		(fp_line
			(start 0.67945 -0.3048)
			(end 0.67945 0.3048)
			(stroke
				(width 0.1)
				(type default)
			)
			(layer "F.Fab")
		)
		(fp_line
			(start 0.67945 0.3048)
			(end 0.120396 0.3048)
			(stroke
				(width 0.1)
				(type default)
			)
			(layer "F.Fab")
		)
		(pad "1" smd circle
			(at -0.40005 0)
			(size 0 0)
			(layers "F.Cu" "F.Mask" "F.Paste")
			(net "GND")
		)
		(pad "2" smd circle
			(at 0.40005 0)
			(size 0 0)
			(layers "F.Cu" "F.Mask" "F.Paste")
			(net "PVDDCR_CPU0_P0_LSET3")
		)
	)
)
